FILE_TYPE = MULTI_PHYS_TABLE;
PART 'AST1250'
{===============================================================================================================================================================================================================}
:PACK_TYPE | MATERIAL | PART_NUMBER     = EnvComp | PART_NUMBER  | JEDEC_TYPE        | DESCRIPTION                           | CLASS | COMPONENT_TYPE | HEIGHT     | LPID  |SPEED_URL | Status |RPL| AML | Bus_Unit | Days ;
{===============================================================================================================================================================================================================}
'BGA'      | 'IC'     | 'G85138-002'(!) = 'YES;YES;YES;UNK;ok;VLD' | 'G85138-002' | 'BGA408_2_8MA'    | 'IC,VLSI,OTHER,AST1250A0,A1,TFBGA408' | 'IC'  | 'BGA'          | '0.051 IN' |'2519' |'http://speed.intel.com:8081/speed/module/pdm/item/pdm_item_detail_direct.asp?item_cde=G85138-002&item_rev=01&url_param=unused' | 'Design' | 'NO' | '1' | 'SMO_IC' | '???' 
'BGA'      | 'EMPTY'  | 'G85138-002'(!) = 'YES;YES;YES;UNK;ok;VLD' | 'G85138-002' | 'BGA408_2_8MA'    | 'IC,VLSI,OTHER,AST1250A0,A1,TFBGA408' | 'IO'  | 'BGA'          | '0.051 IN' |'2519' |'http://speed.intel.com:8081/speed/module/pdm/item/pdm_item_detail_direct.asp?item_cde=G85138-002&item_rev=01&url_param=unused' | 'Design' | 'NO' | '1' | 'SMO_IC' | '???' 
END_PART
END.
